(kicad_pcb
	(version 20260206)
	(generator "pcbnew")
	(generator_version "10.0")
	(general
		(thickness 1.6)
		(legacy_teardrops no)
	)
	(paper "A4")
	(title_block
		(title "timecard-production-celestica-r4006 — R4006-B0001-02_R01.brd")
		(comment 1 "Time Appliance Project (Time Card) / footprints 733-737 of 1113")
	)
	(layers
		(0 "F.Cu" signal "TOP")
		(4 "In1.Cu" signal "L02_GND1")
		(6 "In2.Cu" signal "L03_SIG1")
		(8 "In3.Cu" signal "L04_GND2")
		(10 "In4.Cu" signal "L05_VCC1")
		(12 "In5.Cu" signal "L06_VCC2")
		(14 "In6.Cu" signal "L07_GND3")
		(16 "In7.Cu" signal "L08_SIG2")
		(18 "In8.Cu" signal "L09_GND4")
		(2 "B.Cu" signal "BOTTOM")
		(9 "F.Adhes" user "F.Adhesive")
		(11 "B.Adhes" user "B.Adhesive")
		(13 "F.Paste" user "Package Geometry/Pastemask Top")
		(15 "B.Paste" user "Package Geometry/Pastemask Bottom")
		(5 "F.SilkS" user "Ref Des/Silkscreen Top")
		(7 "B.SilkS" user "Ref Des/Silkscreen Bottom")
		(1 "F.Mask" user "Board Geometry/Soldermask Top")
		(3 "B.Mask" user "Board Geometry/Soldermask Bottom")
		(17 "Dwgs.User" user "User.Drawings")
		(19 "Cmts.User" user "User.Comments")
		(21 "Eco1.User" user "User.Eco1")
		(23 "Eco2.User" user "User.Eco2")
		(25 "Edge.Cuts" user "Board Geometry/Outline")
		(27 "Margin" user)
		(31 "F.CrtYd" user "Package Geometry/Place Bound Top")
		(29 "B.CrtYd" user "Package Geometry/Place Bound Bottom")
		(35 "F.Fab" user "Ref Des/Assembly Top")
		(33 "B.Fab" user "Ref Des/Assembly Bottom")
	)
	(footprint ""
		(layer "B.Cu")
		(at 112.346994 -48.823118)
		(property "Reference" "C132"
			(at -0.078994 -0.929132 0)
			(unlocked yes)
			(layer "B.SilkS")
			(effects
				(font
					(size 0.635 0.4064)
					(thickness 0.1524)
				)
				(justify mirror)
			)
		)
		(property "Value" "VAL*"
			(at 0 3.718306 0)
			(unlocked yes)
			(layer "B.Fab")
			(hide yes)
			(effects
				(font
					(size 0.7874 0.5842)
					(thickness 0.127)
				)
				(justify mirror)
			)
		)
		(property "Device Type" "CAPACITOR-G105-0B104-CK,0.1UF,A"
			(at 0 1.432306 0)
			(unlocked yes)
			(layer "B.Fab")
			(hide yes)
			(effects
				(font
					(size 0.7874 0.5842)
					(thickness 0.127)
				)
				(justify mirror)
			)
		)
		(property "User Part Number" "PARTNUM*"
			(at 0 2.575306 0)
			(unlocked yes)
			(layer "Cmts.User")
			(hide yes)
			(effects
				(font
					(size 0.7874 0.5842)
					(thickness 0.127)
				)
				(justify mirror)
			)
		)
		(property "Tolerance" "TOL*"
			(at 0 4.861306 0)
			(unlocked yes)
			(layer "Cmts.User")
			(hide yes)
			(effects
				(font
					(size 0.7874 0.5842)
					(thickness 0.127)
				)
				(justify mirror)
			)
		)
		(duplicate_pad_numbers_are_jumpers no)
		(fp_line
			(start -0.970026 -0.4699)
			(end -0.970026 0.4699)
			(stroke
				(width 0.1)
				(type default)
			)
			(layer "B.SilkS")
		)
		(fp_line
			(start -0.970026 0.4699)
			(end 0.970026 0.4699)
			(stroke
				(width 0.1)
				(type default)
			)
			(layer "B.SilkS")
		)
		(fp_line
			(start 0.970026 -0.4699)
			(end -0.970026 -0.4699)
			(stroke
				(width 0.1)
				(type default)
			)
			(layer "B.SilkS")
		)
		(fp_line
			(start 0.970026 0.4699)
			(end 0.970026 -0.4699)
			(stroke
				(width 0.1)
				(type default)
			)
			(layer "B.SilkS")
		)
		(fp_poly
			(pts
				(xy 0.970026 0.4699) (xy -0.970026 0.4699) (xy -0.970026 -0.4699) (xy 0.970026 -0.4699)
			)
			(stroke
				(width 0)
				(type default)
			)
			(fill no)
			(layer "B.CrtYd")
		)
		(fp_line
			(start -0.508 -0.3048)
			(end -0.508 0.3048)
			(stroke
				(width 0.1)
				(type default)
			)
			(layer "B.Fab")
		)
		(fp_line
			(start -0.508 0.3048)
			(end 0.508 0.3048)
			(stroke
				(width 0.1)
				(type default)
			)
			(layer "B.Fab")
		)
		(fp_line
			(start 0.508 -0.3048)
			(end -0.508 -0.3048)
			(stroke
				(width 0.1)
				(type default)
			)
			(layer "B.Fab")
		)
		(fp_line
			(start 0.508 0.3048)
			(end 0.508 -0.3048)
			(stroke
				(width 0.1)
				(type default)
			)
			(layer "B.Fab")
		)
		(pad "1" smd circle
			(at 0.500126 0 180)
			(size 0.635 0.635)
			(layers "B.Cu" "B.Mask" "B.Paste")
			(net "XP3R3V_FPGA")
		)
		(pad "2" smd circle
			(at -0.500126 0 180)
			(size 0.635 0.635)
			(layers "B.Cu" "B.Mask" "B.Paste")
			(net "SG")
		)
	)
	(footprint ""
		(layer "B.Cu")
		(at 115.443 -73.533 180)
		(property "Reference" "C294"
			(at 0.127 2.37363 0)
			(unlocked yes)
			(layer "B.SilkS")
			(effects
				(font
					(size 0.7874 0.5842)
					(thickness 0.1524)
				)
				(justify mirror)
			)
		)
		(property "Value" "VAL*"
			(at -0.0762 2.067306 180)
			(unlocked yes)
			(layer "B.Fab")
			(hide yes)
			(effects
				(font
					(size 0.7874 0.5842)
					(thickness 0.1524)
				)
				(justify mirror)
			)
		)
		(property "Tolerance" "TOL*"
			(at -0.0762 3.032506 180)
			(unlocked yes)
			(layer "Cmts.User")
			(hide yes)
			(effects
				(font
					(size 0.7874 0.5842)
					(thickness 0.1524)
				)
				(justify mirror)
			)
		)
		(property "User Part Number" "PARTNUM*"
			(at -0.1016 4.023106 180)
			(unlocked yes)
			(layer "Cmts.User")
			(hide yes)
			(effects
				(font
					(size 0.7874 0.5842)
					(thickness 0.1524)
				)
				(justify mirror)
			)
		)
		(property "Device Type" "CAPACITOR-G105-0B224-DK,0.22UFA"
			(at -0.0508 1.127506 180)
			(unlocked yes)
			(layer "B.Fab")
			(hide yes)
			(effects
				(font
					(size 0.7874 0.5842)
					(thickness 0.1524)
				)
				(justify mirror)
			)
		)
		(duplicate_pad_numbers_are_jumpers no)
		(fp_line
			(start 1.143 0.5588)
			(end -1.143 0.5588)
			(stroke
				(width 0.1)
				(type default)
			)
			(layer "B.SilkS")
		)
		(fp_line
			(start 1.143 -0.5588)
			(end 1.143 0.5588)
			(stroke
				(width 0.1)
				(type default)
			)
			(layer "B.SilkS")
		)
		(fp_line
			(start -1.143 0.5588)
			(end -1.143 -0.5588)
			(stroke
				(width 0.1)
				(type default)
			)
			(layer "B.SilkS")
		)
		(fp_line
			(start -1.143 -0.5588)
			(end 1.143 -0.5588)
			(stroke
				(width 0.1)
				(type default)
			)
			(layer "B.SilkS")
		)
		(fp_rect
			(start 1.143 -0.5588)
			(end -1.143 0.5588)
			(stroke
				(width 0)
				(type default)
			)
			(fill no)
			(layer "B.CrtYd")
		)
		(fp_line
			(start 0.508 0.3048)
			(end -0.508 0.3048)
			(stroke
				(width 0.1)
				(type default)
			)
			(layer "B.Fab")
		)
		(fp_line
			(start 0.508 -0.3048)
			(end 0.508 0.3048)
			(stroke
				(width 0.1)
				(type default)
			)
			(layer "B.Fab")
		)
		(fp_line
			(start -0.508 0.3048)
			(end -0.508 -0.3048)
			(stroke
				(width 0.1)
				(type default)
			)
			(layer "B.Fab")
		)
		(fp_line
			(start -0.508 -0.3048)
			(end 0.508 -0.3048)
			(stroke
				(width 0.1)
				(type default)
			)
			(layer "B.Fab")
		)
		(pad "1" smd rect
			(at 0.5334 0)
			(size 0.7112 0.6096)
			(layers "B.Cu" "B.Mask" "B.Paste")
			(net "XP3R3V_FPGA_EN_R")
		)
		(pad "2" smd rect
			(at -0.5334 0)
			(size 0.7112 0.6096)
			(layers "B.Cu" "B.Mask" "B.Paste")
			(net "SG")
		)
		(zone
			(layer "B.Cu")
			(hatch none 0.5)
			(connect_pads
				(clearance 0)
			)
			(min_thickness 0.25)
			(keepout
				(tracks allowed)
				(vias not_allowed)
				(pads allowed)
				(copperpour not_allowed)
				(footprints allowed)
			)
			(placement
				(enabled no)
				(sheetname "")
			)
			(fill
				(thermal_gap 0.5)
				(thermal_bridge_width 0.5)
				(island_removal_mode 0)
			)
			(polygon
				(pts
					(xy 115.3668 -73.2282) (xy 115.5192 -73.2282) (xy 115.5192 -73.8378) (xy 115.3668 -73.8378)
				)
			)
		)
		(zone
			(layer "B.Cu")
			(hatch none 0.5)
			(connect_pads
				(clearance 0)
			)
			(min_thickness 0.25)
			(keepout
				(tracks not_allowed)
				(vias allowed)
				(pads allowed)
				(copperpour not_allowed)
				(footprints allowed)
			)
			(placement
				(enabled no)
				(sheetname "")
			)
			(fill
				(thermal_gap 0.5)
				(thermal_bridge_width 0.5)
				(island_removal_mode 0)
			)
			(polygon
				(pts
					(xy 115.3668 -73.2282) (xy 115.5192 -73.2282) (xy 115.5192 -73.8378) (xy 115.3668 -73.8378)
				)
			)
		)
	)
	(footprint ""
		(layer "B.Cu")
		(at 18.288 -74.041)
		(property "Reference" "R340"
			(at 0 3.34137 0)
			(unlocked yes)
			(layer "B.SilkS")
			(effects
				(font
					(size 0.7874 0.5842)
					(thickness 0.1524)
				)
				(justify mirror)
			)
		)
		(property "Value" "VAL*"
			(at -0.02032 2.13233 0)
			(unlocked yes)
			(layer "B.Fab")
			(hide yes)
			(effects
				(font
					(size 0.7874 0.5842)
					(thickness 0.1524)
				)
				(justify mirror)
			)
		)
		(property "Tolerance" "TOL*"
			(at -0.044704 3.05435 0)
			(unlocked yes)
			(layer "Cmts.User")
			(hide yes)
			(effects
				(font
					(size 0.7874 0.5842)
					(thickness 0.1524)
				)
				(justify mirror)
			)
		)
		(property "User Part Number" "PARTNUM*"
			(at -0.02032 4.024884 0)
			(unlocked yes)
			(layer "Cmts.User")
			(hide yes)
			(effects
				(font
					(size 0.7874 0.5842)
					(thickness 0.1524)
				)
				(justify mirror)
			)
		)
		(property "Device Type" "RESISTOR-G155-14701-01,4.7KOHMA"
			(at -0.008382 1.210564 0)
			(unlocked yes)
			(layer "B.Fab")
			(hide yes)
			(effects
				(font
					(size 0.7874 0.5842)
					(thickness 0.1524)
				)
				(justify mirror)
			)
		)
		(duplicate_pad_numbers_are_jumpers no)
		(fp_line
			(start -1.143 -0.5588)
			(end 1.143 -0.5588)
			(stroke
				(width 0.1)
				(type default)
			)
			(layer "B.SilkS")
		)
		(fp_line
			(start -1.143 0.5588)
			(end -1.143 -0.5588)
			(stroke
				(width 0.1)
				(type default)
			)
			(layer "B.SilkS")
		)
		(fp_line
			(start 1.143 -0.5588)
			(end 1.143 0.5588)
			(stroke
				(width 0.1)
				(type default)
			)
			(layer "B.SilkS")
		)
		(fp_line
			(start 1.143 0.5588)
			(end -1.143 0.5588)
			(stroke
				(width 0.1)
				(type default)
			)
			(layer "B.SilkS")
		)
		(fp_rect
			(start 1.143 -0.5588)
			(end -1.143 0.5588)
			(stroke
				(width 0)
				(type default)
			)
			(fill no)
			(layer "B.CrtYd")
		)
		(fp_line
			(start -0.508 -0.3048)
			(end 0.508 -0.3048)
			(stroke
				(width 0.1)
				(type default)
			)
			(layer "B.Fab")
		)
		(fp_line
			(start -0.508 0.3048)
			(end -0.508 -0.3048)
			(stroke
				(width 0.1)
				(type default)
			)
			(layer "B.Fab")
		)
		(fp_line
			(start 0.508 -0.3048)
			(end 0.508 0.3048)
			(stroke
				(width 0.1)
				(type default)
			)
			(layer "B.Fab")
		)
		(fp_line
			(start 0.508 0.3048)
			(end -0.508 0.3048)
			(stroke
				(width 0.1)
				(type default)
			)
			(layer "B.Fab")
		)
		(pad "1" smd rect
			(at 0.5334 0 180)
			(size 0.7112 0.6096)
			(layers "B.Cu" "B.Mask" "B.Paste")
			(net "XP3R3V_FPGA")
		)
		(pad "2" smd rect
			(at -0.5334 0 180)
			(size 0.7112 0.6096)
			(layers "B.Cu" "B.Mask" "B.Paste")
			(net "FPGA_IN_LM75B_INT1_N")
		)
		(zone
			(layer "B.Cu")
			(hatch none 0.5)
			(connect_pads
				(clearance 0)
			)
			(min_thickness 0.25)
			(keepout
				(tracks allowed)
				(vias not_allowed)
				(pads allowed)
				(copperpour not_allowed)
				(footprints allowed)
			)
			(placement
				(enabled no)
				(sheetname "")
			)
			(fill
				(thermal_gap 0.5)
				(thermal_bridge_width 0.5)
				(island_removal_mode 0)
			)
			(polygon
				(pts
					(xy 18.3642 -74.3458) (xy 18.2118 -74.3458) (xy 18.2118 -73.7362) (xy 18.3642 -73.7362)
				)
			)
		)
	)
	(footprint ""
		(layer "B.Cu")
		(at 20.447 -61.5442 90)
		(property "Reference" "R316"
			(at -0.3302 -3.97637 270)
			(unlocked yes)
			(layer "B.SilkS")
			(effects
				(font
					(size 0.7874 0.5842)
					(thickness 0.1524)
				)
				(justify mirror)
			)
		)
		(property "Value" "VAL*"
			(at -0.02032 2.13233 90)
			(unlocked yes)
			(layer "B.Fab")
			(hide yes)
			(effects
				(font
					(size 0.7874 0.5842)
					(thickness 0.1524)
				)
				(justify mirror)
			)
		)
		(property "Tolerance" "TOL*"
			(at -0.044704 3.05435 90)
			(unlocked yes)
			(layer "Cmts.User")
			(hide yes)
			(effects
				(font
					(size 0.7874 0.5842)
					(thickness 0.1524)
				)
				(justify mirror)
			)
		)
		(property "User Part Number" "PARTNUM*"
			(at -0.02032 4.024884 90)
			(unlocked yes)
			(layer "Cmts.User")
			(hide yes)
			(effects
				(font
					(size 0.7874 0.5842)
					(thickness 0.1524)
				)
				(justify mirror)
			)
		)
		(property "Device Type" "RESISTOR-G155-100R0-J0,0OHM,-"
			(at -0.008382 1.210564 90)
			(unlocked yes)
			(layer "B.Fab")
			(hide yes)
			(effects
				(font
					(size 0.7874 0.5842)
					(thickness 0.1524)
				)
				(justify mirror)
			)
		)
		(duplicate_pad_numbers_are_jumpers no)
		(fp_line
			(start 1.143 -0.5588)
			(end 1.143 0.5588)
			(stroke
				(width 0.1)
				(type default)
			)
			(layer "B.SilkS")
		)
		(fp_line
			(start -1.143 -0.5588)
			(end 1.143 -0.5588)
			(stroke
				(width 0.1)
				(type default)
			)
			(layer "B.SilkS")
		)
		(fp_line
			(start 1.143 0.5588)
			(end -1.143 0.5588)
			(stroke
				(width 0.1)
				(type default)
			)
			(layer "B.SilkS")
		)
		(fp_line
			(start -1.143 0.5588)
			(end -1.143 -0.5588)
			(stroke
				(width 0.1)
				(type default)
			)
			(layer "B.SilkS")
		)
		(fp_poly
			(pts
				(xy 1.143 0.5588) (xy -1.143 0.5588) (xy -1.143 -0.5588) (xy 1.143 -0.5588)
			)
			(stroke
				(width 0)
				(type default)
			)
			(fill no)
			(layer "B.CrtYd")
		)
		(fp_line
			(start 0.508 -0.3048)
			(end 0.508 0.3048)
			(stroke
				(width 0.1)
				(type default)
			)
			(layer "B.Fab")
		)
		(fp_line
			(start -0.508 -0.3048)
			(end 0.508 -0.3048)
			(stroke
				(width 0.1)
				(type default)
			)
			(layer "B.Fab")
		)
		(fp_line
			(start 0.508 0.3048)
			(end -0.508 0.3048)
			(stroke
				(width 0.1)
				(type default)
			)
			(layer "B.Fab")
		)
		(fp_line
			(start -0.508 0.3048)
			(end -0.508 -0.3048)
			(stroke
				(width 0.1)
				(type default)
			)
			(layer "B.Fab")
		)
		(pad "1" smd rect
			(at 0.5334 0 270)
			(size 0.7112 0.6096)
			(layers "B.Cu" "B.Mask" "B.Paste")
			(net "ICP10100_I2C_SDA")
		)
		(pad "2" smd rect
			(at -0.5334 0 270)
			(size 0.7112 0.6096)
			(layers "B.Cu" "B.Mask" "B.Paste")
			(net "BF_ICP10100_I2C_SDA")
		)
		(zone
			(layer "B.Cu")
			(hatch none 0.5)
			(connect_pads
				(clearance 0)
			)
			(min_thickness 0.25)
			(keepout
				(tracks not_allowed)
				(vias allowed)
				(pads allowed)
				(copperpour not_allowed)
				(footprints allowed)
			)
			(placement
				(enabled no)
				(sheetname "")
			)
			(fill
				(thermal_gap 0.5)
				(thermal_bridge_width 0.5)
				(island_removal_mode 0)
			)
			(polygon
				(pts
					(xy 20.7518 -61.6204) (xy 20.1422 -61.6204) (xy 20.1422 -61.468) (xy 20.7518 -61.468)
				)
			)
		)
		(zone
			(layer "B.Cu")
			(hatch none 0.5)
			(connect_pads
				(clearance 0)
			)
			(min_thickness 0.25)
			(keepout
				(tracks allowed)
				(vias not_allowed)
				(pads allowed)
				(copperpour not_allowed)
				(footprints allowed)
			)
			(placement
				(enabled no)
				(sheetname "")
			)
			(fill
				(thermal_gap 0.5)
				(thermal_bridge_width 0.5)
				(island_removal_mode 0)
			)
			(polygon
				(pts
					(xy 20.7518 -61.6204) (xy 20.1422 -61.6204) (xy 20.1422 -61.468) (xy 20.7518 -61.468)
				)
			)
		)
	)
	(footprint ""
		(layer "B.Cu")
		(at 21.082 -16.891)
		(property "Reference" "R3"
			(at 0.381 1.69037 0)
			(unlocked yes)
			(layer "B.SilkS")
			(effects
				(font
					(size 0.7874 0.5842)
					(thickness 0.1524)
				)
				(justify mirror)
			)
		)
		(property "Value" "VAL*"
			(at -0.02032 2.13233 0)
			(unlocked yes)
			(layer "B.Fab")
			(hide yes)
			(effects
				(font
					(size 0.7874 0.5842)
					(thickness 0.1524)
				)
				(justify mirror)
			)
		)
		(property "Device Type" "RESISTOR-G155-14701-01,4.7KOHMA"
			(at -0.008382 1.210564 0)
			(unlocked yes)
			(layer "B.Fab")
			(hide yes)
			(effects
				(font
					(size 0.7874 0.5842)
					(thickness 0.1524)
				)
				(justify mirror)
			)
		)
		(property "User Part Number" "PARTNUM*"
			(at -0.02032 4.024884 0)
			(unlocked yes)
			(layer "Cmts.User")
			(hide yes)
			(effects
				(font
					(size 0.7874 0.5842)
					(thickness 0.1524)
				)
				(justify mirror)
			)
		)
		(property "Tolerance" "TOL*"
			(at -0.044704 3.05435 0)
			(unlocked yes)
			(layer "Cmts.User")
			(hide yes)
			(effects
				(font
					(size 0.7874 0.5842)
					(thickness 0.1524)
				)
				(justify mirror)
			)
		)
		(duplicate_pad_numbers_are_jumpers no)
		(fp_line
			(start -1.143 -0.5588)
			(end 1.143 -0.5588)
			(stroke
				(width 0.1)
				(type default)
			)
			(layer "B.SilkS")
		)
		(fp_line
			(start -1.143 0.5588)
			(end -1.143 -0.5588)
			(stroke
				(width 0.1)
				(type default)
			)
			(layer "B.SilkS")
		)
		(fp_line
			(start 1.143 -0.5588)
			(end 1.143 0.5588)
			(stroke
				(width 0.1)
				(type default)
			)
			(layer "B.SilkS")
		)
		(fp_line
			(start 1.143 0.5588)
			(end -1.143 0.5588)
			(stroke
				(width 0.1)
				(type default)
			)
			(layer "B.SilkS")
		)
		(fp_rect
			(start -1.143 -0.5588)
			(end 1.143 0.5588)
			(stroke
				(width 0)
				(type default)
			)
			(fill no)
			(layer "B.CrtYd")
		)
		(fp_line
			(start -0.508 -0.3048)
			(end 0.508 -0.3048)
			(stroke
				(width 0.1)
				(type default)
			)
			(layer "B.Fab")
		)
		(fp_line
			(start -0.508 0.3048)
			(end -0.508 -0.3048)
			(stroke
				(width 0.1)
				(type default)
			)
			(layer "B.Fab")
		)
		(fp_line
			(start 0.508 -0.3048)
			(end 0.508 0.3048)
			(stroke
				(width 0.1)
				(type default)
			)
			(layer "B.Fab")
		)
		(fp_line
			(start 0.508 0.3048)
			(end -0.508 0.3048)
			(stroke
				(width 0.1)
				(type default)
			)
			(layer "B.Fab")
		)
		(pad "1" smd rect
			(at 0.5334 0 180)
			(size 0.7112 0.6096)
			(layers "B.Cu" "B.Mask" "B.Paste")
			(net "XP3R3V_FPGA")
		)
		(pad "2" smd rect
			(at -0.5334 0 180)
			(size 0.7112 0.6096)
			(layers "B.Cu" "B.Mask" "B.Paste")
			(net "SEC_EEPROM_WP")
		)
		(zone
			(layer "B.Cu")
			(hatch none 0.5)
			(connect_pads
				(clearance 0)
			)
			(min_thickness 0.25)
			(keepout
				(tracks allowed)
				(vias not_allowed)
				(pads allowed)
				(copperpour not_allowed)
				(footprints allowed)
			)
			(placement
				(enabled no)
				(sheetname "")
			)
			(fill
				(thermal_gap 0.5)
				(thermal_bridge_width 0.5)
				(island_removal_mode 0)
			)
			(polygon
				(pts
					(xy 21.0058 -17.1958) (xy 21.0058 -16.5862) (xy 21.1582 -16.5862) (xy 21.1582 -17.1958)
				)
			)
		)
	)
)
